(kicad_pcb
	(version 20260206)
	(generator "pcbnew")
	(generator_version "10.0")
	(general
		(thickness 1.6)
		(legacy_teardrops no)
	)
	(paper "A4")
	(title_block
		(title "timecard-production-celestica-r4006 — R4006-B0001-02_R01.brd")
		(comment 1 "Time Appliance Project (Time Card) / footprints 887-891 of 1113")
	)
	(layers
		(0 "F.Cu" signal "TOP")
		(4 "In1.Cu" signal "L02_GND1")
		(6 "In2.Cu" signal "L03_SIG1")
		(8 "In3.Cu" signal "L04_GND2")
		(10 "In4.Cu" signal "L05_VCC1")
		(12 "In5.Cu" signal "L06_VCC2")
		(14 "In6.Cu" signal "L07_GND3")
		(16 "In7.Cu" signal "L08_SIG2")
		(18 "In8.Cu" signal "L09_GND4")
		(2 "B.Cu" signal "BOTTOM")
		(9 "F.Adhes" user "F.Adhesive")
		(11 "B.Adhes" user "B.Adhesive")
		(13 "F.Paste" user "Package Geometry/Pastemask Top")
		(15 "B.Paste" user "Package Geometry/Pastemask Bottom")
		(5 "F.SilkS" user "Ref Des/Silkscreen Top")
		(7 "B.SilkS" user "Ref Des/Silkscreen Bottom")
		(1 "F.Mask" user "Board Geometry/Soldermask Top")
		(3 "B.Mask" user "Board Geometry/Soldermask Bottom")
		(17 "Dwgs.User" user "User.Drawings")
		(19 "Cmts.User" user "User.Comments")
		(21 "Eco1.User" user "User.Eco1")
		(23 "Eco2.User" user "User.Eco2")
		(25 "Edge.Cuts" user "Board Geometry/Outline")
		(27 "Margin" user)
		(31 "F.CrtYd" user "Package Geometry/Place Bound Top")
		(29 "B.CrtYd" user "Package Geometry/Place Bound Bottom")
		(35 "F.Fab" user "Ref Des/Assembly Top")
		(33 "B.Fab" user "Ref Des/Assembly Bottom")
	)
	(footprint ""
		(layer "B.Cu")
		(at 100.346764 -51.823112)
		(property "Reference" "C157"
			(at -2.175764 0.038862 0)
			(unlocked yes)
			(layer "B.SilkS")
			(effects
				(font
					(size 0.635 0.4064)
					(thickness 0.1524)
				)
				(justify mirror)
			)
		)
		(property "Value" "VAL*"
			(at 0 3.718306 0)
			(unlocked yes)
			(layer "B.Fab")
			(hide yes)
			(effects
				(font
					(size 0.7874 0.5842)
					(thickness 0.127)
				)
				(justify mirror)
			)
		)
		(property "Device Type" "CAPACITOR-G105-0B104-CK,0.1UF,A"
			(at 0 1.432306 0)
			(unlocked yes)
			(layer "B.Fab")
			(hide yes)
			(effects
				(font
					(size 0.7874 0.5842)
					(thickness 0.127)
				)
				(justify mirror)
			)
		)
		(property "User Part Number" "PARTNUM*"
			(at 0 2.575306 0)
			(unlocked yes)
			(layer "Cmts.User")
			(hide yes)
			(effects
				(font
					(size 0.7874 0.5842)
					(thickness 0.127)
				)
				(justify mirror)
			)
		)
		(property "Tolerance" "TOL*"
			(at 0 4.861306 0)
			(unlocked yes)
			(layer "Cmts.User")
			(hide yes)
			(effects
				(font
					(size 0.7874 0.5842)
					(thickness 0.127)
				)
				(justify mirror)
			)
		)
		(duplicate_pad_numbers_are_jumpers no)
		(fp_line
			(start -0.970026 -0.4699)
			(end -0.970026 0.4699)
			(stroke
				(width 0.1)
				(type default)
			)
			(layer "B.SilkS")
		)
		(fp_line
			(start -0.970026 0.4699)
			(end 0.970026 0.4699)
			(stroke
				(width 0.1)
				(type default)
			)
			(layer "B.SilkS")
		)
		(fp_line
			(start 0.970026 -0.4699)
			(end -0.970026 -0.4699)
			(stroke
				(width 0.1)
				(type default)
			)
			(layer "B.SilkS")
		)
		(fp_line
			(start 0.970026 0.4699)
			(end 0.970026 -0.4699)
			(stroke
				(width 0.1)
				(type default)
			)
			(layer "B.SilkS")
		)
		(fp_poly
			(pts
				(xy 0.970026 0.4699) (xy -0.970026 0.4699) (xy -0.970026 -0.4699) (xy 0.970026 -0.4699)
			)
			(stroke
				(width 0)
				(type default)
			)
			(fill no)
			(layer "B.CrtYd")
		)
		(fp_line
			(start -0.508 -0.3048)
			(end -0.508 0.3048)
			(stroke
				(width 0.1)
				(type default)
			)
			(layer "B.Fab")
		)
		(fp_line
			(start -0.508 0.3048)
			(end 0.508 0.3048)
			(stroke
				(width 0.1)
				(type default)
			)
			(layer "B.Fab")
		)
		(fp_line
			(start 0.508 -0.3048)
			(end -0.508 -0.3048)
			(stroke
				(width 0.1)
				(type default)
			)
			(layer "B.Fab")
		)
		(fp_line
			(start 0.508 0.3048)
			(end 0.508 -0.3048)
			(stroke
				(width 0.1)
				(type default)
			)
			(layer "B.Fab")
		)
		(pad "1" smd circle
			(at 0.500126 0 180)
			(size 0.635 0.635)
			(layers "B.Cu" "B.Mask" "B.Paste")
			(net "XP3R3V_FPGA")
		)
		(pad "2" smd circle
			(at -0.500126 0 180)
			(size 0.635 0.635)
			(layers "B.Cu" "B.Mask" "B.Paste")
			(net "SG")
		)
	)
	(footprint ""
		(layer "B.Cu")
		(at 105.41 -64.2874 90)
		(property "Reference" "R328"
			(at 3.5306 -0.16637 270)
			(unlocked yes)
			(layer "B.SilkS")
			(effects
				(font
					(size 0.7874 0.5842)
					(thickness 0.1524)
				)
				(justify mirror)
			)
		)
		(property "Value" "VAL*"
			(at -0.02032 2.13233 90)
			(unlocked yes)
			(layer "B.Fab")
			(hide yes)
			(effects
				(font
					(size 0.7874 0.5842)
					(thickness 0.1524)
				)
				(justify mirror)
			)
		)
		(property "Tolerance" "TOL*"
			(at -0.044704 3.05435 90)
			(unlocked yes)
			(layer "Cmts.User")
			(hide yes)
			(effects
				(font
					(size 0.7874 0.5842)
					(thickness 0.1524)
				)
				(justify mirror)
			)
		)
		(property "User Part Number" "PARTNUM*"
			(at -0.02032 4.024884 90)
			(unlocked yes)
			(layer "Cmts.User")
			(hide yes)
			(effects
				(font
					(size 0.7874 0.5842)
					(thickness 0.1524)
				)
				(justify mirror)
			)
		)
		(property "Device Type" "RESISTOR-G155-14701-01,4.7KOHMA"
			(at -0.008382 1.210564 90)
			(unlocked yes)
			(layer "B.Fab")
			(hide yes)
			(effects
				(font
					(size 0.7874 0.5842)
					(thickness 0.1524)
				)
				(justify mirror)
			)
		)
		(duplicate_pad_numbers_are_jumpers no)
		(fp_line
			(start 1.143 -0.5588)
			(end 1.143 0.5588)
			(stroke
				(width 0.1)
				(type default)
			)
			(layer "B.SilkS")
		)
		(fp_line
			(start -1.143 -0.5588)
			(end 1.143 -0.5588)
			(stroke
				(width 0.1)
				(type default)
			)
			(layer "B.SilkS")
		)
		(fp_line
			(start 1.143 0.5588)
			(end -1.143 0.5588)
			(stroke
				(width 0.1)
				(type default)
			)
			(layer "B.SilkS")
		)
		(fp_line
			(start -1.143 0.5588)
			(end -1.143 -0.5588)
			(stroke
				(width 0.1)
				(type default)
			)
			(layer "B.SilkS")
		)
		(fp_poly
			(pts
				(xy 1.143 0.5588) (xy -1.143 0.5588) (xy -1.143 -0.5588) (xy 1.143 -0.5588)
			)
			(stroke
				(width 0)
				(type default)
			)
			(fill no)
			(layer "B.CrtYd")
		)
		(fp_line
			(start 0.508 -0.3048)
			(end 0.508 0.3048)
			(stroke
				(width 0.1)
				(type default)
			)
			(layer "B.Fab")
		)
		(fp_line
			(start -0.508 -0.3048)
			(end 0.508 -0.3048)
			(stroke
				(width 0.1)
				(type default)
			)
			(layer "B.Fab")
		)
		(fp_line
			(start 0.508 0.3048)
			(end -0.508 0.3048)
			(stroke
				(width 0.1)
				(type default)
			)
			(layer "B.Fab")
		)
		(fp_line
			(start -0.508 0.3048)
			(end -0.508 -0.3048)
			(stroke
				(width 0.1)
				(type default)
			)
			(layer "B.Fab")
		)
		(pad "1" smd rect
			(at 0.5334 0 270)
			(size 0.7112 0.6096)
			(layers "B.Cu" "B.Mask" "B.Paste")
			(net "SG")
		)
		(pad "2" smd rect
			(at -0.5334 0 270)
			(size 0.7112 0.6096)
			(layers "B.Cu" "B.Mask" "B.Paste")
			(net "FPGA_IO_7")
		)
		(zone
			(layer "B.Cu")
			(hatch none 0.5)
			(connect_pads
				(clearance 0)
			)
			(min_thickness 0.25)
			(keepout
				(tracks allowed)
				(vias not_allowed)
				(pads allowed)
				(copperpour not_allowed)
				(footprints allowed)
			)
			(placement
				(enabled no)
				(sheetname "")
			)
			(fill
				(thermal_gap 0.5)
				(thermal_bridge_width 0.5)
				(island_removal_mode 0)
			)
			(polygon
				(pts
					(xy 105.7148 -64.3636) (xy 105.1052 -64.3636) (xy 105.1052 -64.2112) (xy 105.7148 -64.2112)
				)
			)
		)
		(zone
			(layer "B.Cu")
			(hatch none 0.5)
			(connect_pads
				(clearance 0)
			)
			(min_thickness 0.25)
			(keepout
				(tracks not_allowed)
				(vias allowed)
				(pads allowed)
				(copperpour not_allowed)
				(footprints allowed)
			)
			(placement
				(enabled no)
				(sheetname "")
			)
			(fill
				(thermal_gap 0.5)
				(thermal_bridge_width 0.5)
				(island_removal_mode 0)
			)
			(polygon
				(pts
					(xy 105.7148 -64.3636) (xy 105.1052 -64.3636) (xy 105.1052 -64.2112) (xy 105.7148 -64.2112)
				)
			)
		)
	)
	(footprint ""
		(layer "B.Cu")
		(at 125.349 -89.535 -90)
		(property "Reference" "R110"
			(at -3.683 -0.08763 270)
			(unlocked yes)
			(layer "B.SilkS")
			(effects
				(font
					(size 0.7874 0.5842)
					(thickness 0.1524)
				)
				(justify mirror)
			)
		)
		(property "Value" "VAL*"
			(at -0.02032 2.13233 270)
			(unlocked yes)
			(layer "B.Fab")
			(hide yes)
			(effects
				(font
					(size 0.7874 0.5842)
					(thickness 0.1524)
				)
				(justify mirror)
			)
		)
		(property "Device Type" "RESISTOR-G155-133R0-01,33OHM,1%"
			(at -0.008382 1.210564 270)
			(unlocked yes)
			(layer "B.Fab")
			(hide yes)
			(effects
				(font
					(size 0.7874 0.5842)
					(thickness 0.1524)
				)
				(justify mirror)
			)
		)
		(property "User Part Number" "PARTNUM*"
			(at -0.02032 4.024884 270)
			(unlocked yes)
			(layer "Cmts.User")
			(hide yes)
			(effects
				(font
					(size 0.7874 0.5842)
					(thickness 0.1524)
				)
				(justify mirror)
			)
		)
		(property "Tolerance" "TOL*"
			(at -0.044704 3.05435 270)
			(unlocked yes)
			(layer "Cmts.User")
			(hide yes)
			(effects
				(font
					(size 0.7874 0.5842)
					(thickness 0.1524)
				)
				(justify mirror)
			)
		)
		(duplicate_pad_numbers_are_jumpers no)
		(fp_line
			(start -1.143 0.5588)
			(end -1.143 -0.5588)
			(stroke
				(width 0.1)
				(type default)
			)
			(layer "B.SilkS")
		)
		(fp_line
			(start 1.143 0.5588)
			(end -1.143 0.5588)
			(stroke
				(width 0.1)
				(type default)
			)
			(layer "B.SilkS")
		)
		(fp_line
			(start -1.143 -0.5588)
			(end 1.143 -0.5588)
			(stroke
				(width 0.1)
				(type default)
			)
			(layer "B.SilkS")
		)
		(fp_line
			(start 1.143 -0.5588)
			(end 1.143 0.5588)
			(stroke
				(width 0.1)
				(type default)
			)
			(layer "B.SilkS")
		)
		(fp_rect
			(start -1.143 -0.5588)
			(end 1.143 0.5588)
			(stroke
				(width 0)
				(type default)
			)
			(fill no)
			(layer "B.CrtYd")
		)
		(fp_line
			(start -0.508 0.3048)
			(end -0.508 -0.3048)
			(stroke
				(width 0.1)
				(type default)
			)
			(layer "B.Fab")
		)
		(fp_line
			(start 0.508 0.3048)
			(end -0.508 0.3048)
			(stroke
				(width 0.1)
				(type default)
			)
			(layer "B.Fab")
		)
		(fp_line
			(start -0.508 -0.3048)
			(end 0.508 -0.3048)
			(stroke
				(width 0.1)
				(type default)
			)
			(layer "B.Fab")
		)
		(fp_line
			(start 0.508 -0.3048)
			(end 0.508 0.3048)
			(stroke
				(width 0.1)
				(type default)
			)
			(layer "B.Fab")
		)
		(pad "1" smd rect
			(at 0.5334 0 90)
			(size 0.7112 0.6096)
			(layers "B.Cu" "B.Mask" "B.Paste")
			(net "UART_GPS_RX_FPGA_TX")
		)
		(pad "2" smd rect
			(at -0.5334 0 90)
			(size 0.7112 0.6096)
			(layers "B.Cu" "B.Mask" "B.Paste")
			(net "GPS_UART_RXD")
		)
		(zone
			(layer "B.Cu")
			(hatch none 0.5)
			(connect_pads
				(clearance 0)
			)
			(min_thickness 0.25)
			(keepout
				(tracks allowed)
				(vias not_allowed)
				(pads allowed)
				(copperpour not_allowed)
				(footprints allowed)
			)
			(placement
				(enabled no)
				(sheetname "")
			)
			(fill
				(thermal_gap 0.5)
				(thermal_bridge_width 0.5)
				(island_removal_mode 0)
			)
			(polygon
				(pts
					(xy 125.6538 -89.6112) (xy 125.0442 -89.6112) (xy 125.0442 -89.4588) (xy 125.6538 -89.4588)
				)
			)
		)
	)
	(footprint ""
		(layer "B.Cu")
		(at 70.993 -47.2186 -90)
		(property "Reference" "R90"
			(at -0.0254 1.05537 270)
			(unlocked yes)
			(layer "B.SilkS")
			(effects
				(font
					(size 0.7874 0.5842)
					(thickness 0.1524)
				)
				(justify mirror)
			)
		)
		(property "Value" "VAL*"
			(at -0.02032 2.13233 270)
			(unlocked yes)
			(layer "B.Fab")
			(hide yes)
			(effects
				(font
					(size 0.7874 0.5842)
					(thickness 0.1524)
				)
				(justify mirror)
			)
		)
		(property "Device Type" "RESISTOR-G155-11000-01,100OHM,A"
			(at -0.008382 1.210564 270)
			(unlocked yes)
			(layer "B.Fab")
			(hide yes)
			(effects
				(font
					(size 0.7874 0.5842)
					(thickness 0.1524)
				)
				(justify mirror)
			)
		)
		(property "User Part Number" "PARTNUM*"
			(at -0.02032 4.024884 270)
			(unlocked yes)
			(layer "Cmts.User")
			(hide yes)
			(effects
				(font
					(size 0.7874 0.5842)
					(thickness 0.1524)
				)
				(justify mirror)
			)
		)
		(property "Tolerance" "TOL*"
			(at -0.044704 3.05435 270)
			(unlocked yes)
			(layer "Cmts.User")
			(hide yes)
			(effects
				(font
					(size 0.7874 0.5842)
					(thickness 0.1524)
				)
				(justify mirror)
			)
		)
		(duplicate_pad_numbers_are_jumpers no)
		(fp_line
			(start -1.143 0.5588)
			(end -1.143 -0.5588)
			(stroke
				(width 0.1)
				(type default)
			)
			(layer "B.SilkS")
		)
		(fp_line
			(start 1.143 0.5588)
			(end -1.143 0.5588)
			(stroke
				(width 0.1)
				(type default)
			)
			(layer "B.SilkS")
		)
		(fp_line
			(start -1.143 -0.5588)
			(end 1.143 -0.5588)
			(stroke
				(width 0.1)
				(type default)
			)
			(layer "B.SilkS")
		)
		(fp_line
			(start 1.143 -0.5588)
			(end 1.143 0.5588)
			(stroke
				(width 0.1)
				(type default)
			)
			(layer "B.SilkS")
		)
		(fp_rect
			(start 1.143 -0.5588)
			(end -1.143 0.5588)
			(stroke
				(width 0)
				(type default)
			)
			(fill no)
			(layer "B.CrtYd")
		)
		(fp_line
			(start -0.508 0.3048)
			(end -0.508 -0.3048)
			(stroke
				(width 0.1)
				(type default)
			)
			(layer "B.Fab")
		)
		(fp_line
			(start 0.508 0.3048)
			(end -0.508 0.3048)
			(stroke
				(width 0.1)
				(type default)
			)
			(layer "B.Fab")
		)
		(fp_line
			(start -0.508 -0.3048)
			(end 0.508 -0.3048)
			(stroke
				(width 0.1)
				(type default)
			)
			(layer "B.Fab")
		)
		(fp_line
			(start 0.508 -0.3048)
			(end 0.508 0.3048)
			(stroke
				(width 0.1)
				(type default)
			)
			(layer "B.Fab")
		)
		(pad "1" smd rect
			(at 0.5334 0 90)
			(size 0.7112 0.6096)
			(layers "B.Cu" "B.Mask" "B.Paste")
			(net "R_MAC_PPS_IN0N")
		)
		(pad "2" smd rect
			(at -0.5334 0 90)
			(size 0.7112 0.6096)
			(layers "B.Cu" "B.Mask" "B.Paste")
			(net "R_MAC_PPS_IN0P")
		)
		(zone
			(layer "B.Cu")
			(hatch none 0.5)
			(connect_pads
				(clearance 0)
			)
			(min_thickness 0.25)
			(keepout
				(tracks allowed)
				(vias not_allowed)
				(pads allowed)
				(copperpour not_allowed)
				(footprints allowed)
			)
			(placement
				(enabled no)
				(sheetname "")
			)
			(fill
				(thermal_gap 0.5)
				(thermal_bridge_width 0.5)
				(island_removal_mode 0)
			)
			(polygon
				(pts
					(xy 71.2978 -47.1424) (xy 71.2978 -47.2948) (xy 70.6882 -47.2948) (xy 70.6882 -47.1424)
				)
			)
		)
	)
	(footprint ""
		(layer "B.Cu")
		(at 5.588 -78.105 180)
		(property "Reference" "C39"
			(at 3.048 0.08763 0)
			(unlocked yes)
			(layer "B.SilkS")
			(effects
				(font
					(size 0.7874 0.5842)
					(thickness 0.1524)
				)
				(justify mirror)
			)
		)
		(property "Value" "VAL*"
			(at -0.0762 2.067306 180)
			(unlocked yes)
			(layer "B.Fab")
			(hide yes)
			(effects
				(font
					(size 0.7874 0.5842)
					(thickness 0.1524)
				)
				(justify mirror)
			)
		)
		(property "Tolerance" "TOL*"
			(at -0.0762 3.032506 180)
			(unlocked yes)
			(layer "Cmts.User")
			(hide yes)
			(effects
				(font
					(size 0.7874 0.5842)
					(thickness 0.1524)
				)
				(justify mirror)
			)
		)
		(property "User Part Number" "PARTNUM*"
			(at -0.1016 4.023106 180)
			(unlocked yes)
			(layer "Cmts.User")
			(hide yes)
			(effects
				(font
					(size 0.7874 0.5842)
					(thickness 0.1524)
				)
				(justify mirror)
			)
		)
		(property "Device Type" "CAPACITOR-G105-0B104-EK,0.1UF,A"
			(at -0.0508 1.127506 180)
			(unlocked yes)
			(layer "B.Fab")
			(hide yes)
			(effects
				(font
					(size 0.7874 0.5842)
					(thickness 0.1524)
				)
				(justify mirror)
			)
		)
		(duplicate_pad_numbers_are_jumpers no)
		(fp_line
			(start 1.143 0.5588)
			(end -1.143 0.5588)
			(stroke
				(width 0.1)
				(type default)
			)
			(layer "B.SilkS")
		)
		(fp_line
			(start 1.143 -0.5588)
			(end 1.143 0.5588)
			(stroke
				(width 0.1)
				(type default)
			)
			(layer "B.SilkS")
		)
		(fp_line
			(start -1.143 0.5588)
			(end -1.143 -0.5588)
			(stroke
				(width 0.1)
				(type default)
			)
			(layer "B.SilkS")
		)
		(fp_line
			(start -1.143 -0.5588)
			(end 1.143 -0.5588)
			(stroke
				(width 0.1)
				(type default)
			)
			(layer "B.SilkS")
		)
		(fp_rect
			(start -1.143 0.5588)
			(end 1.143 -0.5588)
			(stroke
				(width 0)
				(type default)
			)
			(fill no)
			(layer "B.CrtYd")
		)
		(fp_line
			(start 0.508 0.3048)
			(end -0.508 0.3048)
			(stroke
				(width 0.1)
				(type default)
			)
			(layer "B.Fab")
		)
		(fp_line
			(start 0.508 -0.3048)
			(end 0.508 0.3048)
			(stroke
				(width 0.1)
				(type default)
			)
			(layer "B.Fab")
		)
		(fp_line
			(start -0.508 0.3048)
			(end -0.508 -0.3048)
			(stroke
				(width 0.1)
				(type default)
			)
			(layer "B.Fab")
		)
		(fp_line
			(start -0.508 -0.3048)
			(end 0.508 -0.3048)
			(stroke
				(width 0.1)
				(type default)
			)
			(layer "B.Fab")
		)
		(pad "1" smd rect
			(at 0.5334 0)
			(size 0.7112 0.6096)
			(layers "B.Cu" "B.Mask" "B.Paste")
			(net "SG")
		)
		(pad "2" smd rect
			(at -0.5334 0)
			(size 0.7112 0.6096)
			(layers "B.Cu" "B.Mask" "B.Paste")
			(net "XP3R3V_FPGA")
		)
		(zone
			(layer "B.Cu")
			(hatch none 0.5)
			(connect_pads
				(clearance 0)
			)
			(min_thickness 0.25)
			(keepout
				(tracks allowed)
				(vias not_allowed)
				(pads allowed)
				(copperpour not_allowed)
				(footprints allowed)
			)
			(placement
				(enabled no)
				(sheetname "")
			)
			(fill
				(thermal_gap 0.5)
				(thermal_bridge_width 0.5)
				(island_removal_mode 0)
			)
			(polygon
				(pts
					(xy 5.6642 -78.4098) (xy 5.5118 -78.4098) (xy 5.5118 -77.8002) (xy 5.6642 -77.8002)
				)
			)
		)
	)
)
